FILE_TYPE=LIBRARY_PARTS;
primitive 'DIODE_TVS';
  pin
    'A':
      PIN_NUMBER='(A)';
      INPUT_LOAD='(-0.01,0.01)';
    'C':
      PIN_NUMBER='(C)';
      OUTPUT_LOAD='(1.0,-1.0)';
  end_pin;
  body
    PART_NAME='DIODE_TVS';
    BODY_NAME='DIODE_TVS';
    PHYS_DES_PREFIX='D';
    CLASS='DISCRETE';
  end_body;
end_primitive;

END.
